(kicad_pcb
	(version 20260206)
	(generator "pcbnew")
	(generator_version "10.0")
	(general
		(thickness 1.6)
		(legacy_teardrops no)
	)
	(paper "A4")
	(title_block
		(title "9052_F0T_PDB_Converter_Brick_F_V03_1208_1600_OCP.brd")
		(comment 1 "Grand Teton / footprints 529-534 of 578")
	)
	(layers
		(0 "F.Cu" signal "TOP")
		(4 "In1.Cu" signal "GND")
		(6 "In2.Cu" signal "IN1")
		(8 "In3.Cu" signal "GND1")
		(10 "In4.Cu" signal "VCC")
		(12 "In5.Cu" signal "VCC1")
		(14 "In6.Cu" signal "GND2")
		(16 "In7.Cu" signal "IN2")
		(18 "In8.Cu" signal "GND3")
		(2 "B.Cu" signal "BOTTOM")
		(9 "F.Adhes" user "F.Adhesive")
		(11 "B.Adhes" user "B.Adhesive")
		(13 "F.Paste" user "Package Geometry/Pastemask Top")
		(15 "B.Paste" user "Package Geometry/Pastemask Bottom")
		(5 "F.SilkS" user "Ref Des/Silkscreen Top")
		(7 "B.SilkS" user "Ref Des/Silkscreen Bottom")
		(1 "F.Mask" user "Board Geometry/Soldermask Top")
		(3 "B.Mask" user "Board Geometry/Soldermask Bottom")
		(17 "Dwgs.User" user "User.Drawings")
		(19 "Cmts.User" user "User.Comments")
		(21 "Eco1.User" user "User.Eco1")
		(23 "Eco2.User" user "User.Eco2")
		(25 "Edge.Cuts" user "Board Geometry/Outline")
		(27 "Margin" user)
		(31 "F.CrtYd" user "Package Geometry/Place Bound Top")
		(29 "B.CrtYd" user "Package Geometry/Place Bound Bottom")
		(35 "F.Fab" user "Ref Des/Assembly Top")
		(33 "B.Fab" user "Ref Des/Assembly Bottom")
	)
	(footprint ""
		(layer "B.Cu")
		(at 273.5072 -103.759 90)
		(property "Reference" "R5860"
			(at 0 0 90)
			(layer "B.SilkS")
			(hide yes)
			(effects
				(font
					(size 1.27 1.27)
				)
				(justify mirror)
			)
		)
		(property "Value" ""
			(at 0 0 90)
			(layer "B.Fab")
			(effects
				(font
					(size 1.27 1.27)
				)
				(justify mirror)
			)
		)
		(duplicate_pad_numbers_are_jumpers no)
		(fp_line
			(start 0.7874 -0.4064)
			(end -0.7874 -0.4064)
			(stroke
				(width 0.1524)
				(type default)
			)
			(layer "B.SilkS")
		)
		(fp_line
			(start -0.7874 -0.4064)
			(end -0.7874 0.4064)
			(stroke
				(width 0.1524)
				(type default)
			)
			(layer "B.SilkS")
		)
		(fp_line
			(start 0.7874 0.4064)
			(end 0.7874 -0.4064)
			(stroke
				(width 0.1524)
				(type default)
			)
			(layer "B.SilkS")
		)
		(fp_line
			(start -0.7874 0.4064)
			(end 0.7874 0.4064)
			(stroke
				(width 0.1524)
				(type default)
			)
			(layer "B.SilkS")
		)
		(fp_line
			(start 0.67945 -0.305054)
			(end 0.12065 -0.305054)
			(stroke
				(width 0.1)
				(type default)
			)
			(layer "B.Fab")
		)
		(fp_line
			(start 0.12065 -0.305054)
			(end 0.12065 -0.2794)
			(stroke
				(width 0.1)
				(type default)
			)
			(layer "B.Fab")
		)
		(fp_line
			(start -0.12065 -0.3048)
			(end -0.67945 -0.3048)
			(stroke
				(width 0.1)
				(type default)
			)
			(layer "B.Fab")
		)
		(fp_line
			(start -0.67945 -0.3048)
			(end -0.67945 0.3048)
			(stroke
				(width 0.1)
				(type default)
			)
			(layer "B.Fab")
		)
		(fp_line
			(start 0.12065 -0.2794)
			(end -0.12065 -0.2794)
			(stroke
				(width 0.1)
				(type default)
			)
			(layer "B.Fab")
		)
		(fp_line
			(start -0.12065 -0.2794)
			(end -0.12065 -0.3048)
			(stroke
				(width 0.1)
				(type default)
			)
			(layer "B.Fab")
		)
		(fp_line
			(start 0.12065 0.2794)
			(end 0.12065 0.3048)
			(stroke
				(width 0.1)
				(type default)
			)
			(layer "B.Fab")
		)
		(fp_line
			(start -0.120396 0.2794)
			(end 0.12065 0.2794)
			(stroke
				(width 0.1)
				(type default)
			)
			(layer "B.Fab")
		)
		(fp_line
			(start 0.67945 0.3048)
			(end 0.67945 -0.305054)
			(stroke
				(width 0.1)
				(type default)
			)
			(layer "B.Fab")
		)
		(fp_line
			(start 0.12065 0.3048)
			(end 0.67945 0.3048)
			(stroke
				(width 0.1)
				(type default)
			)
			(layer "B.Fab")
		)
		(fp_line
			(start -0.120396 0.3048)
			(end -0.120396 0.2794)
			(stroke
				(width 0.1)
				(type default)
			)
			(layer "B.Fab")
		)
		(fp_line
			(start -0.67945 0.3048)
			(end -0.120396 0.3048)
			(stroke
				(width 0.1)
				(type default)
			)
			(layer "B.Fab")
		)
		(pad "1" smd circle
			(at 0.40005 0 270)
			(size 0 0)
			(layers "B.Cu" "B.Mask" "B.Paste")
			(net "P52V_HS1_GATE1_R")
		)
		(pad "2" smd circle
			(at -0.40005 0 270)
			(size 0 0)
			(layers "B.Cu" "B.Mask" "B.Paste")
			(net "P52V_HS1_1272_GATE")
		)
	)
	(footprint ""
		(layer "B.Cu")
		(at 227.076 -74.93 180)
		(property "Reference" "U27"
			(at -0.508 2.25933 0)
			(unlocked yes)
			(layer "B.SilkS")
			(effects
				(font
					(size 0.7874 0.5842)
					(thickness 0.1524)
				)
				(justify left mirror)
			)
		)
		(property "Value" ""
			(at 0 0 0)
			(layer "B.Fab")
			(effects
				(font
					(size 1.27 1.27)
				)
				(justify mirror)
			)
		)
		(duplicate_pad_numbers_are_jumpers no)
		(fp_line
			(start 1.603248 1.500124)
			(end 1.603248 -1.500124)
			(stroke
				(width 0.1524)
				(type default)
			)
			(layer "B.SilkS")
		)
		(fp_line
			(start 1.603248 -1.500124)
			(end -1.603248 -1.500124)
			(stroke
				(width 0.1524)
				(type default)
			)
			(layer "B.SilkS")
		)
		(fp_line
			(start -1.603248 1.500124)
			(end 1.603248 1.500124)
			(stroke
				(width 0.1524)
				(type default)
			)
			(layer "B.SilkS")
		)
		(fp_line
			(start -1.603248 -1.500124)
			(end -1.603248 1.500124)
			(stroke
				(width 0.1524)
				(type default)
			)
			(layer "B.SilkS")
		)
		(fp_line
			(start 1.249934 1.169924)
			(end 0.700024 1.169924)
			(stroke
				(width 0.1)
				(type default)
			)
			(layer "B.Fab")
		)
		(fp_line
			(start 1.249934 0.729996)
			(end 1.249934 1.169924)
			(stroke
				(width 0.1)
				(type default)
			)
			(layer "B.Fab")
		)
		(fp_line
			(start 1.249934 -0.729996)
			(end 0.6985 -0.729996)
			(stroke
				(width 0.1)
				(type default)
			)
			(layer "B.Fab")
		)
		(fp_line
			(start 1.249934 -1.169924)
			(end 1.249934 -0.729996)
			(stroke
				(width 0.1)
				(type default)
			)
			(layer "B.Fab")
		)
		(fp_line
			(start 0.700024 1.500124)
			(end -0.700024 1.500124)
			(stroke
				(width 0.1)
				(type default)
			)
			(layer "B.Fab")
		)
		(fp_line
			(start 0.700024 1.169924)
			(end 0.700024 1.500124)
			(stroke
				(width 0.1)
				(type default)
			)
			(layer "B.Fab")
		)
		(fp_line
			(start 0.700024 -1.169924)
			(end 1.249934 -1.169924)
			(stroke
				(width 0.1)
				(type default)
			)
			(layer "B.Fab")
		)
		(fp_line
			(start 0.700024 -1.500124)
			(end 0.700024 -1.169924)
			(stroke
				(width 0.1)
				(type default)
			)
			(layer "B.Fab")
		)
		(fp_line
			(start 0.6985 0.729996)
			(end 1.249934 0.729996)
			(stroke
				(width 0.1)
				(type default)
			)
			(layer "B.Fab")
		)
		(fp_line
			(start 0.6985 -0.729996)
			(end 0.6985 0.729996)
			(stroke
				(width 0.1)
				(type default)
			)
			(layer "B.Fab")
		)
		(fp_line
			(start -0.700024 1.500124)
			(end -0.700024 0.219964)
			(stroke
				(width 0.1)
				(type default)
			)
			(layer "B.Fab")
		)
		(fp_line
			(start -0.700024 0.219964)
			(end -1.249934 0.219964)
			(stroke
				(width 0.1)
				(type default)
			)
			(layer "B.Fab")
		)
		(fp_line
			(start -0.700024 -0.219964)
			(end -0.700024 -1.500124)
			(stroke
				(width 0.1)
				(type default)
			)
			(layer "B.Fab")
		)
		(fp_line
			(start -0.700024 -1.500124)
			(end 0.700024 -1.500124)
			(stroke
				(width 0.1)
				(type default)
			)
			(layer "B.Fab")
		)
		(fp_line
			(start -1.249934 0.219964)
			(end -1.249934 -0.219964)
			(stroke
				(width 0.1)
				(type default)
			)
			(layer "B.Fab")
		)
		(fp_line
			(start -1.249934 -0.219964)
			(end -0.700024 -0.219964)
			(stroke
				(width 0.1)
				(type default)
			)
			(layer "B.Fab")
		)
		(fp_rect
			(start 0.700024 -1.500124)
			(end -0.700024 1.500124)
			(stroke
				(width 0)
				(type default)
			)
			(fill no)
			(layer "B.Fab")
		)
		(pad "D" smd rect
			(at -0.999998 0 90)
			(size 0.8128 0.9144)
			(layers "B.Cu" "B.Mask" "B.Paste")
			(net "P12V_BRICK_PWRGD_N")
		)
		(pad "G" smd rect
			(at 0.999998 -0.94996 90)
			(size 0.8128 0.9144)
			(layers "B.Cu" "B.Mask" "B.Paste")
			(net "P12V_BRICK_PWRGD")
		)
		(pad "S" smd rect
			(at 0.999998 0.94996 90)
			(size 0.8128 0.9144)
			(layers "B.Cu" "B.Mask" "B.Paste")
			(net "GND")
		)
	)
	(footprint ""
		(layer "B.Cu")
		(at 278.388318 -154.315668 90)
		(property "Reference" "J11"
			(at 1.386332 -5.633974 270)
			(unlocked yes)
			(layer "B.SilkS")
			(effects
				(font
					(size 0.7874 0.5842)
					(thickness 0.1524)
				)
				(justify left mirror)
			)
		)
		(property "Value" ""
			(at 0 0 90)
			(layer "B.Fab")
			(effects
				(font
					(size 1.27 1.27)
				)
				(justify mirror)
			)
		)
		(duplicate_pad_numbers_are_jumpers no)
		(fp_line
			(start 3.330702 -4.771136)
			(end -3.330702 -4.771136)
			(stroke
				(width 0.1524)
				(type default)
			)
			(layer "B.SilkS")
		)
		(fp_line
			(start -3.330702 -4.771136)
			(end 0 4.011168)
			(stroke
				(width 0.1524)
				(type default)
			)
			(layer "B.SilkS")
		)
		(fp_line
			(start 0 4.011168)
			(end 3.330702 -4.771136)
			(stroke
				(width 0.1524)
				(type default)
			)
			(layer "B.SilkS")
		)
		(fp_line
			(start 3.330702 -4.771136)
			(end -3.330702 -4.771136)
			(stroke
				(width 0.1)
				(type default)
			)
			(layer "B.Fab")
		)
		(fp_line
			(start -3.330702 -4.771136)
			(end 0 4.011168)
			(stroke
				(width 0.1)
				(type default)
			)
			(layer "B.Fab")
		)
		(fp_line
			(start 0 4.011168)
			(end 3.330702 -4.771136)
			(stroke
				(width 0.1)
				(type default)
			)
			(layer "B.Fab")
		)
		(pad "1" thru_hole circle
			(at 0 0 270)
			(size 2.159 2.159)
			(drill 1.7018)
			(layers "*.Cu" "*.Mask")
			(remove_unused_layers no)
			(net "GND3")
			(clearance 0.0254)
			(thermal_gap 0.0254)
		)
		(pad "2" thru_hole circle
			(at 1.27 -3.348736 270)
			(size 2.159 2.159)
			(drill 1.7018)
			(layers "*.Cu" "*.Mask")
			(remove_unused_layers no)
			(net "TDR_SE_50_OHM_BOT")
			(clearance 0.0254)
			(thermal_gap 0.0254)
		)
		(pad "3" thru_hole circle
			(at -1.27 -3.348736 270)
			(size 2.159 2.159)
			(drill 1.7018)
			(layers "*.Cu" "*.Mask")
			(remove_unused_layers no)
			(net "TDR_SE_50_OHM_BOT")
			(clearance 0.0254)
			(thermal_gap 0.0254)
		)
	)
	(footprint ""
		(layer "B.Cu")
		(at 277.709122 -105.268522 90)
		(property "Reference" "PC8"
			(at 0 0 90)
			(layer "B.SilkS")
			(hide yes)
			(effects
				(font
					(size 1.27 1.27)
				)
				(justify mirror)
			)
		)
		(property "Value" ""
			(at 0 0 90)
			(layer "B.Fab")
			(effects
				(font
					(size 1.27 1.27)
				)
				(justify mirror)
			)
		)
		(duplicate_pad_numbers_are_jumpers no)
		(fp_line
			(start 1.2954 -0.5842)
			(end -1.2954 -0.5842)
			(stroke
				(width 0.1524)
				(type default)
			)
			(layer "B.SilkS")
		)
		(fp_line
			(start -1.2954 -0.5842)
			(end -1.2954 0.5842)
			(stroke
				(width 0.1524)
				(type default)
			)
			(layer "B.SilkS")
		)
		(fp_line
			(start 1.2954 0.5842)
			(end 1.2954 -0.5842)
			(stroke
				(width 0.1524)
				(type default)
			)
			(layer "B.SilkS")
		)
		(fp_line
			(start -1.2954 0.5842)
			(end 1.2954 0.5842)
			(stroke
				(width 0.1524)
				(type default)
			)
			(layer "B.SilkS")
		)
		(fp_line
			(start 0.8636 -0.4572)
			(end -0.8636 -0.4572)
			(stroke
				(width 0.1)
				(type default)
			)
			(layer "B.Fab")
		)
		(fp_line
			(start -0.8636 -0.4572)
			(end -0.8636 -0.4064)
			(stroke
				(width 0.1)
				(type default)
			)
			(layer "B.Fab")
		)
		(fp_line
			(start 1.1938 -0.4064)
			(end 0.8636 -0.4064)
			(stroke
				(width 0.1)
				(type default)
			)
			(layer "B.Fab")
		)
		(fp_line
			(start 0.8636 -0.4064)
			(end 0.8636 -0.4572)
			(stroke
				(width 0.1)
				(type default)
			)
			(layer "B.Fab")
		)
		(fp_line
			(start -0.8636 -0.4064)
			(end -1.1938 -0.4064)
			(stroke
				(width 0.1)
				(type default)
			)
			(layer "B.Fab")
		)
		(fp_line
			(start -1.1938 -0.4064)
			(end -1.1938 0.4064)
			(stroke
				(width 0.1)
				(type default)
			)
			(layer "B.Fab")
		)
		(fp_line
			(start 1.1938 0.4064)
			(end 1.1938 -0.4064)
			(stroke
				(width 0.1)
				(type default)
			)
			(layer "B.Fab")
		)
		(fp_line
			(start 0.8636 0.4064)
			(end 1.1938 0.4064)
			(stroke
				(width 0.1)
				(type default)
			)
			(layer "B.Fab")
		)
		(fp_line
			(start -0.8636 0.4064)
			(end -0.8636 0.4572)
			(stroke
				(width 0.1)
				(type default)
			)
			(layer "B.Fab")
		)
		(fp_line
			(start -1.1938 0.4064)
			(end -0.8636 0.4064)
			(stroke
				(width 0.1)
				(type default)
			)
			(layer "B.Fab")
		)
		(fp_line
			(start 0.8636 0.4572)
			(end 0.8636 0.4064)
			(stroke
				(width 0.1)
				(type default)
			)
			(layer "B.Fab")
		)
		(fp_line
			(start -0.8636 0.4572)
			(end 0.8636 0.4572)
			(stroke
				(width 0.1)
				(type default)
			)
			(layer "B.Fab")
		)
		(pad "1" smd rect
			(at 0.7366 0)
			(size 0.7112 0.8128)
			(layers "B.Cu" "B.Mask" "B.Paste")
			(net "GND")
		)
		(pad "2" smd rect
			(at -0.7366 0)
			(size 0.7112 0.8128)
			(layers "B.Cu" "B.Mask" "B.Paste")
			(net "P52V_HS1_GATE_R1")
		)
	)
	(footprint ""
		(layer "B.Cu")
		(at 214.884 -67.183 90)
		(property "Reference" "R136"
			(at 0 0 90)
			(layer "B.SilkS")
			(hide yes)
			(effects
				(font
					(size 1.27 1.27)
				)
				(justify mirror)
			)
		)
		(property "Value" ""
			(at 0 0 90)
			(layer "B.Fab")
			(effects
				(font
					(size 1.27 1.27)
				)
				(justify mirror)
			)
		)
		(duplicate_pad_numbers_are_jumpers no)
		(fp_line
			(start 0.7874 -0.4064)
			(end -0.7874 -0.4064)
			(stroke
				(width 0.1524)
				(type default)
			)
			(layer "B.SilkS")
		)
		(fp_line
			(start -0.7874 -0.4064)
			(end -0.7874 0.4064)
			(stroke
				(width 0.1524)
				(type default)
			)
			(layer "B.SilkS")
		)
		(fp_line
			(start 0.7874 0.4064)
			(end 0.7874 -0.4064)
			(stroke
				(width 0.1524)
				(type default)
			)
			(layer "B.SilkS")
		)
		(fp_line
			(start -0.7874 0.4064)
			(end 0.7874 0.4064)
			(stroke
				(width 0.1524)
				(type default)
			)
			(layer "B.SilkS")
		)
		(fp_line
			(start 0.67945 -0.305054)
			(end 0.12065 -0.305054)
			(stroke
				(width 0.1)
				(type default)
			)
			(layer "B.Fab")
		)
		(fp_line
			(start 0.12065 -0.305054)
			(end 0.12065 -0.2794)
			(stroke
				(width 0.1)
				(type default)
			)
			(layer "B.Fab")
		)
		(fp_line
			(start -0.12065 -0.3048)
			(end -0.67945 -0.3048)
			(stroke
				(width 0.1)
				(type default)
			)
			(layer "B.Fab")
		)
		(fp_line
			(start -0.67945 -0.3048)
			(end -0.67945 0.3048)
			(stroke
				(width 0.1)
				(type default)
			)
			(layer "B.Fab")
		)
		(fp_line
			(start 0.12065 -0.2794)
			(end -0.12065 -0.2794)
			(stroke
				(width 0.1)
				(type default)
			)
			(layer "B.Fab")
		)
		(fp_line
			(start -0.12065 -0.2794)
			(end -0.12065 -0.3048)
			(stroke
				(width 0.1)
				(type default)
			)
			(layer "B.Fab")
		)
		(fp_line
			(start 0.12065 0.2794)
			(end 0.12065 0.3048)
			(stroke
				(width 0.1)
				(type default)
			)
			(layer "B.Fab")
		)
		(fp_line
			(start -0.120396 0.2794)
			(end 0.12065 0.2794)
			(stroke
				(width 0.1)
				(type default)
			)
			(layer "B.Fab")
		)
		(fp_line
			(start 0.67945 0.3048)
			(end 0.67945 -0.305054)
			(stroke
				(width 0.1)
				(type default)
			)
			(layer "B.Fab")
		)
		(fp_line
			(start 0.12065 0.3048)
			(end 0.67945 0.3048)
			(stroke
				(width 0.1)
				(type default)
			)
			(layer "B.Fab")
		)
		(fp_line
			(start -0.120396 0.3048)
			(end -0.120396 0.2794)
			(stroke
				(width 0.1)
				(type default)
			)
			(layer "B.Fab")
		)
		(fp_line
			(start -0.67945 0.3048)
			(end -0.120396 0.3048)
			(stroke
				(width 0.1)
				(type default)
			)
			(layer "B.Fab")
		)
		(pad "1" smd circle
			(at 0.40005 0 270)
			(size 0 0)
			(layers "B.Cu" "B.Mask" "B.Paste")
			(net "BOARD_ID_2")
		)
		(pad "2" smd circle
			(at -0.40005 0 270)
			(size 0 0)
			(layers "B.Cu" "B.Mask" "B.Paste")
			(net "GND")
		)
	)
	(footprint ""
		(layer "B.Cu")
		(at 176.850294 -116.078 -90)
		(property "Reference" "R195"
			(at 0 0 90)
			(layer "B.SilkS")
			(hide yes)
			(effects
				(font
					(size 1.27 1.27)
				)
				(justify mirror)
			)
		)
		(property "Value" ""
			(at 0 0 90)
			(layer "B.Fab")
			(effects
				(font
					(size 1.27 1.27)
				)
				(justify mirror)
			)
		)
		(duplicate_pad_numbers_are_jumpers no)
		(fp_line
			(start -0.7874 0.4064)
			(end 0.7874 0.4064)
			(stroke
				(width 0.1524)
				(type default)
			)
			(layer "B.SilkS")
		)
		(fp_line
			(start 0.7874 0.4064)
			(end 0.7874 -0.4064)
			(stroke
				(width 0.1524)
				(type default)
			)
			(layer "B.SilkS")
		)
		(fp_line
			(start -0.7874 -0.4064)
			(end -0.7874 0.4064)
			(stroke
				(width 0.1524)
				(type default)
			)
			(layer "B.SilkS")
		)
		(fp_line
			(start 0.7874 -0.4064)
			(end -0.7874 -0.4064)
			(stroke
				(width 0.1524)
				(type default)
			)
			(layer "B.SilkS")
		)
		(fp_line
			(start -0.67945 0.3048)
			(end -0.120396 0.3048)
			(stroke
				(width 0.1)
				(type default)
			)
			(layer "B.Fab")
		)
		(fp_line
			(start -0.120396 0.3048)
			(end -0.120396 0.2794)
			(stroke
				(width 0.1)
				(type default)
			)
			(layer "B.Fab")
		)
		(fp_line
			(start 0.12065 0.3048)
			(end 0.67945 0.3048)
			(stroke
				(width 0.1)
				(type default)
			)
			(layer "B.Fab")
		)
		(fp_line
			(start 0.67945 0.3048)
			(end 0.67945 -0.305054)
			(stroke
				(width 0.1)
				(type default)
			)
			(layer "B.Fab")
		)
		(fp_line
			(start -0.120396 0.2794)
			(end 0.12065 0.2794)
			(stroke
				(width 0.1)
				(type default)
			)
			(layer "B.Fab")
		)
		(fp_line
			(start 0.12065 0.2794)
			(end 0.12065 0.3048)
			(stroke
				(width 0.1)
				(type default)
			)
			(layer "B.Fab")
		)
		(fp_line
			(start -0.12065 -0.2794)
			(end -0.12065 -0.3048)
			(stroke
				(width 0.1)
				(type default)
			)
			(layer "B.Fab")
		)
		(fp_line
			(start 0.12065 -0.2794)
			(end -0.12065 -0.2794)
			(stroke
				(width 0.1)
				(type default)
			)
			(layer "B.Fab")
		)
		(fp_line
			(start -0.67945 -0.3048)
			(end -0.67945 0.3048)
			(stroke
				(width 0.1)
				(type default)
			)
			(layer "B.Fab")
		)
		(fp_line
			(start -0.12065 -0.3048)
			(end -0.67945 -0.3048)
			(stroke
				(width 0.1)
				(type default)
			)
			(layer "B.Fab")
		)
		(fp_line
			(start 0.12065 -0.305054)
			(end 0.12065 -0.2794)
			(stroke
				(width 0.1)
				(type default)
			)
			(layer "B.Fab")
		)
		(fp_line
			(start 0.67945 -0.305054)
			(end 0.12065 -0.305054)
			(stroke
				(width 0.1)
				(type default)
			)
			(layer "B.Fab")
		)
		(pad "1" smd circle
			(at 0.40005 0 90)
			(size 0 0)
			(layers "B.Cu" "B.Mask" "B.Paste")
			(net "BRICK_P12V_1_EN_N")
		)
		(pad "2" smd circle
			(at -0.40005 0 90)
			(size 0 0)
			(layers "B.Cu" "B.Mask" "B.Paste")
			(net "BRICK_P12V2_ON_OFF_R")
		)
	)
)
